(kicad_pcb
	(version 20260206)
	(generator "pcbnew")
	(generator_version "10.0")
	(general
		(thickness 1.6)
		(legacy_teardrops no)
	)
	(paper "A4")
	(title_block
		(title "01162023_DA0F0TEBIF0_F0T_Expander_BD_F_brd_V02_OCP.brd")
		(comment 1 "Grand Teton / footprints 6957-6963 of 9728")
	)
	(layers
		(0 "F.Cu" signal "TOP")
		(4 "In1.Cu" signal "GND")
		(6 "In2.Cu" signal "VCC")
		(8 "In3.Cu" signal "VCC1")
		(10 "In4.Cu" signal "GND1")
		(12 "In5.Cu" signal "IN1")
		(14 "In6.Cu" signal "GND2")
		(16 "In7.Cu" signal "IN2")
		(18 "In8.Cu" signal "GND3")
		(20 "In9.Cu" signal "IN3")
		(22 "In10.Cu" signal "GND4")
		(24 "In11.Cu" signal "IN4")
		(26 "In12.Cu" signal "GND5")
		(28 "In13.Cu" signal "IN5")
		(30 "In14.Cu" signal "GND6")
		(32 "In15.Cu" signal "IN6")
		(34 "In16.Cu" signal "GND7")
		(2 "B.Cu" signal "BOTTOM")
		(9 "F.Adhes" user "F.Adhesive")
		(11 "B.Adhes" user "B.Adhesive")
		(13 "F.Paste" user "Package Geometry/Pastemask Top")
		(15 "B.Paste" user "Package Geometry/Pastemask Bottom")
		(5 "F.SilkS" user "Ref Des/Silkscreen Top")
		(7 "B.SilkS" user "Ref Des/Silkscreen Bottom")
		(1 "F.Mask" user "Board Geometry/Soldermask Top")
		(3 "B.Mask" user "Board Geometry/Soldermask Bottom")
		(17 "Dwgs.User" user "User.Drawings")
		(19 "Cmts.User" user "User.Comments")
		(21 "Eco1.User" user "User.Eco1")
		(23 "Eco2.User" user "User.Eco2")
		(25 "Edge.Cuts" user "Board Geometry/Outline")
		(27 "Margin" user)
		(31 "F.CrtYd" user "Package Geometry/Place Bound Top")
		(29 "B.CrtYd" user "Package Geometry/Place Bound Bottom")
		(35 "F.Fab" user "Ref Des/Assembly Top")
		(33 "B.Fab" user "Ref Des/Assembly Bottom")
	)
	(footprint ""
		(layer "F.Cu")
		(at 139.756642 -17.419574 180)
		(property "Reference" "R1660"
			(at 0 0 180)
			(layer "F.SilkS")
			(hide yes)
			(effects
				(font
					(size 1.27 1.27)
				)
			)
		)
		(property "Value" ""
			(at 0 0 180)
			(layer "F.Fab")
			(effects
				(font
					(size 1.27 1.27)
				)
			)
		)
		(duplicate_pad_numbers_are_jumpers no)
		(fp_line
			(start 0.7874 0.4064)
			(end -0.7874 0.4064)
			(stroke
				(width 0.1524)
				(type default)
			)
			(layer "F.SilkS")
		)
		(fp_line
			(start 0.7874 -0.4064)
			(end 0.7874 0.4064)
			(stroke
				(width 0.1524)
				(type default)
			)
			(layer "F.SilkS")
		)
		(fp_line
			(start -0.7874 0.4064)
			(end -0.7874 -0.4064)
			(stroke
				(width 0.1524)
				(type default)
			)
			(layer "F.SilkS")
		)
		(fp_line
			(start -0.7874 -0.4064)
			(end 0.7874 -0.4064)
			(stroke
				(width 0.1524)
				(type default)
			)
			(layer "F.SilkS")
		)
		(fp_line
			(start 0.67945 0.3048)
			(end 0.120396 0.3048)
			(stroke
				(width 0.1)
				(type default)
			)
			(layer "F.Fab")
		)
		(fp_line
			(start 0.67945 -0.3048)
			(end 0.67945 0.3048)
			(stroke
				(width 0.1)
				(type default)
			)
			(layer "F.Fab")
		)
		(fp_line
			(start 0.12065 -0.2794)
			(end 0.12065 -0.3048)
			(stroke
				(width 0.1)
				(type default)
			)
			(layer "F.Fab")
		)
		(fp_line
			(start 0.12065 -0.3048)
			(end 0.67945 -0.3048)
			(stroke
				(width 0.1)
				(type default)
			)
			(layer "F.Fab")
		)
		(fp_line
			(start 0.120396 0.3048)
			(end 0.120396 0.2794)
			(stroke
				(width 0.1)
				(type default)
			)
			(layer "F.Fab")
		)
		(fp_line
			(start 0.120396 0.2794)
			(end -0.12065 0.2794)
			(stroke
				(width 0.1)
				(type default)
			)
			(layer "F.Fab")
		)
		(fp_line
			(start -0.12065 0.3048)
			(end -0.67945 0.3048)
			(stroke
				(width 0.1)
				(type default)
			)
			(layer "F.Fab")
		)
		(fp_line
			(start -0.12065 0.2794)
			(end -0.12065 0.3048)
			(stroke
				(width 0.1)
				(type default)
			)
			(layer "F.Fab")
		)
		(fp_line
			(start -0.12065 -0.2794)
			(end 0.12065 -0.2794)
			(stroke
				(width 0.1)
				(type default)
			)
			(layer "F.Fab")
		)
		(fp_line
			(start -0.12065 -0.305054)
			(end -0.12065 -0.2794)
			(stroke
				(width 0.1)
				(type default)
			)
			(layer "F.Fab")
		)
		(fp_line
			(start -0.67945 0.3048)
			(end -0.67945 -0.305054)
			(stroke
				(width 0.1)
				(type default)
			)
			(layer "F.Fab")
		)
		(fp_line
			(start -0.67945 -0.305054)
			(end -0.12065 -0.305054)
			(stroke
				(width 0.1)
				(type default)
			)
			(layer "F.Fab")
		)
		(pad "1" smd circle
			(at -0.40005 0 180)
			(size 0 0)
			(layers "F.Cu" "F.Mask" "F.Paste")
			(net "P3V3_SSD4")
		)
		(pad "2" smd circle
			(at 0.40005 0 180)
			(size 0 0)
			(layers "F.Cu" "F.Mask" "F.Paste")
			(net "SMB_ISO_SSD4_SCL")
		)
	)
	(footprint ""
		(layer "F.Cu")
		(at 326.517 -233.553 180)
		(property "Reference" "R4386"
			(at 0 0 180)
			(layer "F.SilkS")
			(hide yes)
			(effects
				(font
					(size 1.27 1.27)
				)
			)
		)
		(property "Value" ""
			(at 0 0 180)
			(layer "F.Fab")
			(effects
				(font
					(size 1.27 1.27)
				)
			)
		)
		(duplicate_pad_numbers_are_jumpers no)
		(fp_line
			(start 0.7874 0.4064)
			(end -0.7874 0.4064)
			(stroke
				(width 0.1524)
				(type default)
			)
			(layer "F.SilkS")
		)
		(fp_line
			(start 0.7874 -0.4064)
			(end 0.7874 0.4064)
			(stroke
				(width 0.1524)
				(type default)
			)
			(layer "F.SilkS")
		)
		(fp_line
			(start -0.7874 0.4064)
			(end -0.7874 -0.4064)
			(stroke
				(width 0.1524)
				(type default)
			)
			(layer "F.SilkS")
		)
		(fp_line
			(start -0.7874 -0.4064)
			(end 0.7874 -0.4064)
			(stroke
				(width 0.1524)
				(type default)
			)
			(layer "F.SilkS")
		)
		(fp_line
			(start 0.67945 0.3048)
			(end 0.120396 0.3048)
			(stroke
				(width 0.1)
				(type default)
			)
			(layer "F.Fab")
		)
		(fp_line
			(start 0.67945 -0.3048)
			(end 0.67945 0.3048)
			(stroke
				(width 0.1)
				(type default)
			)
			(layer "F.Fab")
		)
		(fp_line
			(start 0.12065 -0.2794)
			(end 0.12065 -0.3048)
			(stroke
				(width 0.1)
				(type default)
			)
			(layer "F.Fab")
		)
		(fp_line
			(start 0.12065 -0.3048)
			(end 0.67945 -0.3048)
			(stroke
				(width 0.1)
				(type default)
			)
			(layer "F.Fab")
		)
		(fp_line
			(start 0.120396 0.3048)
			(end 0.120396 0.2794)
			(stroke
				(width 0.1)
				(type default)
			)
			(layer "F.Fab")
		)
		(fp_line
			(start 0.120396 0.2794)
			(end -0.12065 0.2794)
			(stroke
				(width 0.1)
				(type default)
			)
			(layer "F.Fab")
		)
		(fp_line
			(start -0.12065 0.3048)
			(end -0.67945 0.3048)
			(stroke
				(width 0.1)
				(type default)
			)
			(layer "F.Fab")
		)
		(fp_line
			(start -0.12065 0.2794)
			(end -0.12065 0.3048)
			(stroke
				(width 0.1)
				(type default)
			)
			(layer "F.Fab")
		)
		(fp_line
			(start -0.12065 -0.2794)
			(end 0.12065 -0.2794)
			(stroke
				(width 0.1)
				(type default)
			)
			(layer "F.Fab")
		)
		(fp_line
			(start -0.12065 -0.305054)
			(end -0.12065 -0.2794)
			(stroke
				(width 0.1)
				(type default)
			)
			(layer "F.Fab")
		)
		(fp_line
			(start -0.67945 0.3048)
			(end -0.67945 -0.305054)
			(stroke
				(width 0.1)
				(type default)
			)
			(layer "F.Fab")
		)
		(fp_line
			(start -0.67945 -0.305054)
			(end -0.12065 -0.305054)
			(stroke
				(width 0.1)
				(type default)
			)
			(layer "F.Fab")
		)
		(pad "1" smd circle
			(at -0.40005 0 180)
			(size 0 0)
			(layers "F.Cu" "F.Mask" "F.Paste")
			(net "RST_PEX_SYS_BUF_N")
		)
		(pad "2" smd circle
			(at 0.40005 0 180)
			(size 0 0)
			(layers "F.Cu" "F.Mask" "F.Paste")
			(net "RST_PEX_SYS_BUF_R_N")
		)
	)
	(footprint ""
		(layer "F.Cu")
		(at 137.047478 -20.35556)
		(property "Reference" "C3906"
			(at 0 0 0)
			(layer "F.SilkS")
			(hide yes)
			(effects
				(font
					(size 1.27 1.27)
				)
			)
		)
		(property "Value" ""
			(at 0 0 0)
			(layer "F.Fab")
			(effects
				(font
					(size 1.27 1.27)
				)
			)
		)
		(duplicate_pad_numbers_are_jumpers no)
		(fp_line
			(start -0.7874 -0.4064)
			(end 0.7874 -0.4064)
			(stroke
				(width 0.1524)
				(type default)
			)
			(layer "F.SilkS")
		)
		(fp_line
			(start -0.7874 0.4064)
			(end -0.7874 -0.4064)
			(stroke
				(width 0.1524)
				(type default)
			)
			(layer "F.SilkS")
		)
		(fp_line
			(start 0.7874 -0.4064)
			(end 0.7874 0.4064)
			(stroke
				(width 0.1524)
				(type default)
			)
			(layer "F.SilkS")
		)
		(fp_line
			(start 0.7874 0.4064)
			(end -0.7874 0.4064)
			(stroke
				(width 0.1524)
				(type default)
			)
			(layer "F.SilkS")
		)
		(fp_line
			(start -0.67945 -0.305054)
			(end -0.12065 -0.305054)
			(stroke
				(width 0.1)
				(type default)
			)
			(layer "F.Fab")
		)
		(fp_line
			(start -0.67945 0.3048)
			(end -0.67945 -0.305054)
			(stroke
				(width 0.1)
				(type default)
			)
			(layer "F.Fab")
		)
		(fp_line
			(start -0.12065 -0.305054)
			(end -0.12065 -0.2794)
			(stroke
				(width 0.1)
				(type default)
			)
			(layer "F.Fab")
		)
		(fp_line
			(start -0.12065 -0.2794)
			(end 0.12065 -0.2794)
			(stroke
				(width 0.1)
				(type default)
			)
			(layer "F.Fab")
		)
		(fp_line
			(start -0.12065 0.2794)
			(end -0.12065 0.3048)
			(stroke
				(width 0.1)
				(type default)
			)
			(layer "F.Fab")
		)
		(fp_line
			(start -0.12065 0.3048)
			(end -0.67945 0.3048)
			(stroke
				(width 0.1)
				(type default)
			)
			(layer "F.Fab")
		)
		(fp_line
			(start 0.120396 0.2794)
			(end -0.12065 0.2794)
			(stroke
				(width 0.1)
				(type default)
			)
			(layer "F.Fab")
		)
		(fp_line
			(start 0.120396 0.3048)
			(end 0.120396 0.2794)
			(stroke
				(width 0.1)
				(type default)
			)
			(layer "F.Fab")
		)
		(fp_line
			(start 0.12065 -0.3048)
			(end 0.67945 -0.3048)
			(stroke
				(width 0.1)
				(type default)
			)
			(layer "F.Fab")
		)
		(fp_line
			(start 0.12065 -0.2794)
			(end 0.12065 -0.3048)
			(stroke
				(width 0.1)
				(type default)
			)
			(layer "F.Fab")
		)
		(fp_line
			(start 0.67945 -0.3048)
			(end 0.67945 0.3048)
			(stroke
				(width 0.1)
				(type default)
			)
			(layer "F.Fab")
		)
		(fp_line
			(start 0.67945 0.3048)
			(end 0.120396 0.3048)
			(stroke
				(width 0.1)
				(type default)
			)
			(layer "F.Fab")
		)
		(pad "1" smd circle
			(at -0.40005 0)
			(size 0 0)
			(layers "F.Cu" "F.Mask" "F.Paste")
			(net "P12V_SSD4")
		)
		(pad "2" smd circle
			(at 0.40005 0)
			(size 0 0)
			(layers "F.Cu" "F.Mask" "F.Paste")
			(net "GND")
		)
	)
	(footprint ""
		(layer "F.Cu")
		(at 379.59411 -35.264852)
		(property "Reference" "R5700"
			(at 0 0 0)
			(layer "F.SilkS")
			(hide yes)
			(effects
				(font
					(size 1.27 1.27)
				)
			)
		)
		(property "Value" ""
			(at 0 0 0)
			(layer "F.Fab")
			(effects
				(font
					(size 1.27 1.27)
				)
			)
		)
		(duplicate_pad_numbers_are_jumpers no)
		(fp_line
			(start -0.7874 -0.4064)
			(end 0.7874 -0.4064)
			(stroke
				(width 0.1524)
				(type default)
			)
			(layer "F.SilkS")
		)
		(fp_line
			(start -0.7874 0.4064)
			(end -0.7874 -0.4064)
			(stroke
				(width 0.1524)
				(type default)
			)
			(layer "F.SilkS")
		)
		(fp_line
			(start 0.7874 -0.4064)
			(end 0.7874 0.4064)
			(stroke
				(width 0.1524)
				(type default)
			)
			(layer "F.SilkS")
		)
		(fp_line
			(start 0.7874 0.4064)
			(end -0.7874 0.4064)
			(stroke
				(width 0.1524)
				(type default)
			)
			(layer "F.SilkS")
		)
		(fp_line
			(start -0.67945 -0.305054)
			(end -0.12065 -0.305054)
			(stroke
				(width 0.1)
				(type default)
			)
			(layer "F.Fab")
		)
		(fp_line
			(start -0.67945 0.3048)
			(end -0.67945 -0.305054)
			(stroke
				(width 0.1)
				(type default)
			)
			(layer "F.Fab")
		)
		(fp_line
			(start -0.12065 -0.305054)
			(end -0.12065 -0.2794)
			(stroke
				(width 0.1)
				(type default)
			)
			(layer "F.Fab")
		)
		(fp_line
			(start -0.12065 -0.2794)
			(end 0.12065 -0.2794)
			(stroke
				(width 0.1)
				(type default)
			)
			(layer "F.Fab")
		)
		(fp_line
			(start -0.12065 0.2794)
			(end -0.12065 0.3048)
			(stroke
				(width 0.1)
				(type default)
			)
			(layer "F.Fab")
		)
		(fp_line
			(start -0.12065 0.3048)
			(end -0.67945 0.3048)
			(stroke
				(width 0.1)
				(type default)
			)
			(layer "F.Fab")
		)
		(fp_line
			(start 0.120396 0.2794)
			(end -0.12065 0.2794)
			(stroke
				(width 0.1)
				(type default)
			)
			(layer "F.Fab")
		)
		(fp_line
			(start 0.120396 0.3048)
			(end 0.120396 0.2794)
			(stroke
				(width 0.1)
				(type default)
			)
			(layer "F.Fab")
		)
		(fp_line
			(start 0.12065 -0.3048)
			(end 0.67945 -0.3048)
			(stroke
				(width 0.1)
				(type default)
			)
			(layer "F.Fab")
		)
		(fp_line
			(start 0.12065 -0.2794)
			(end 0.12065 -0.3048)
			(stroke
				(width 0.1)
				(type default)
			)
			(layer "F.Fab")
		)
		(fp_line
			(start 0.67945 -0.3048)
			(end 0.67945 0.3048)
			(stroke
				(width 0.1)
				(type default)
			)
			(layer "F.Fab")
		)
		(fp_line
			(start 0.67945 0.3048)
			(end 0.120396 0.3048)
			(stroke
				(width 0.1)
				(type default)
			)
			(layer "F.Fab")
		)
		(pad "1" smd circle
			(at -0.40005 0)
			(size 0 0)
			(layers "F.Cu" "F.Mask" "F.Paste")
			(net "RST_SMB_SSD13_ISO_N")
		)
		(pad "2" smd circle
			(at 0.40005 0)
			(size 0 0)
			(layers "F.Cu" "F.Mask" "F.Paste")
			(net "GND")
		)
	)
	(footprint ""
		(layer "F.Cu")
		(at 484.109776 -522.077696 180)
		(property "Reference" "SCREW_SSD7_2"
			(at -5.207 -1.402334 0)
			(unlocked yes)
			(layer "B.SilkS")
			(effects
				(font
					(size 0.7874 0.5842)
					(thickness 0.1524)
				)
				(justify mirror)
			)
		)
		(property "Value" ""
			(at 0 0 180)
			(layer "F.Fab")
			(effects
				(font
					(size 1.27 1.27)
				)
			)
		)
		(duplicate_pad_numbers_are_jumpers no)
		(pad "1" thru_hole circle
			(at 0 0 180)
			(size 0.4572 0.4572)
			(drill 0.2032)
			(layers "*.Cu" "*.Mask")
			(remove_unused_layers no)
			(net "Net_9129")
			(clearance 0.127)
			(thermal_gap 0.127)
			(padstack
				(mode front_inner_back)
				(layer "Inner"
					(shape circle)
					(size 0.4572 0.4572)
					(clearance 0.127)
				)
				(layer "B.Cu"
					(shape circle)
					(size 0.508 0.508)
					(clearance 0.1016)
				)
			)
		)
	)
	(footprint ""
		(layer "F.Cu")
		(at 349.907098 -285.088584 90)
		(property "Reference" "PC154"
			(at 0 0 90)
			(layer "F.SilkS")
			(hide yes)
			(effects
				(font
					(size 1.27 1.27)
				)
			)
		)
		(property "Value" ""
			(at 0 0 90)
			(layer "F.Fab")
			(effects
				(font
					(size 1.27 1.27)
				)
			)
		)
		(duplicate_pad_numbers_are_jumpers no)
		(fp_line
			(start 0.7874 -0.4064)
			(end 0.7874 0.4064)
			(stroke
				(width 0.1524)
				(type default)
			)
			(layer "F.SilkS")
		)
		(fp_line
			(start -0.7874 -0.4064)
			(end 0.7874 -0.4064)
			(stroke
				(width 0.1524)
				(type default)
			)
			(layer "F.SilkS")
		)
		(fp_line
			(start 0.7874 0.4064)
			(end -0.7874 0.4064)
			(stroke
				(width 0.1524)
				(type default)
			)
			(layer "F.SilkS")
		)
		(fp_line
			(start -0.7874 0.4064)
			(end -0.7874 -0.4064)
			(stroke
				(width 0.1524)
				(type default)
			)
			(layer "F.SilkS")
		)
		(fp_line
			(start -0.12065 -0.305054)
			(end -0.12065 -0.2794)
			(stroke
				(width 0.1)
				(type default)
			)
			(layer "F.Fab")
		)
		(fp_line
			(start -0.67945 -0.305054)
			(end -0.12065 -0.305054)
			(stroke
				(width 0.1)
				(type default)
			)
			(layer "F.Fab")
		)
		(fp_line
			(start 0.67945 -0.3048)
			(end 0.67945 0.3048)
			(stroke
				(width 0.1)
				(type default)
			)
			(layer "F.Fab")
		)
		(fp_line
			(start 0.12065 -0.3048)
			(end 0.67945 -0.3048)
			(stroke
				(width 0.1)
				(type default)
			)
			(layer "F.Fab")
		)
		(fp_line
			(start 0.12065 -0.2794)
			(end 0.12065 -0.3048)
			(stroke
				(width 0.1)
				(type default)
			)
			(layer "F.Fab")
		)
		(fp_line
			(start -0.12065 -0.2794)
			(end 0.12065 -0.2794)
			(stroke
				(width 0.1)
				(type default)
			)
			(layer "F.Fab")
		)
		(fp_line
			(start 0.120396 0.2794)
			(end -0.12065 0.2794)
			(stroke
				(width 0.1)
				(type default)
			)
			(layer "F.Fab")
		)
		(fp_line
			(start -0.12065 0.2794)
			(end -0.12065 0.3048)
			(stroke
				(width 0.1)
				(type default)
			)
			(layer "F.Fab")
		)
		(fp_line
			(start 0.67945 0.3048)
			(end 0.120396 0.3048)
			(stroke
				(width 0.1)
				(type default)
			)
			(layer "F.Fab")
		)
		(fp_line
			(start 0.120396 0.3048)
			(end 0.120396 0.2794)
			(stroke
				(width 0.1)
				(type default)
			)
			(layer "F.Fab")
		)
		(fp_line
			(start -0.12065 0.3048)
			(end -0.67945 0.3048)
			(stroke
				(width 0.1)
				(type default)
			)
			(layer "F.Fab")
		)
		(fp_line
			(start -0.67945 0.3048)
			(end -0.67945 -0.305054)
			(stroke
				(width 0.1)
				(type default)
			)
			(layer "F.Fab")
		)
		(pad "1" smd circle
			(at -0.40005 0 90)
			(size 0 0)
			(layers "F.Cu" "F.Mask" "F.Paste")
			(net "P0V8_PEX2_PVCC")
		)
		(pad "2" smd circle
			(at 0.40005 0 90)
			(size 0 0)
			(layers "F.Cu" "F.Mask" "F.Paste")
			(net "GND")
		)
	)
	(footprint ""
		(layer "F.Cu")
		(at 168.343834 -43.85691)
		(property "Reference" "R563"
			(at 0 0 0)
			(layer "F.SilkS")
			(hide yes)
			(effects
				(font
					(size 1.27 1.27)
				)
			)
		)
		(property "Value" ""
			(at 0 0 0)
			(layer "F.Fab")
			(effects
				(font
					(size 1.27 1.27)
				)
			)
		)
		(duplicate_pad_numbers_are_jumpers no)
		(fp_line
			(start -0.7874 -0.4064)
			(end 0.7874 -0.4064)
			(stroke
				(width 0.1524)
				(type default)
			)
			(layer "F.SilkS")
		)
		(fp_line
			(start -0.7874 0.4064)
			(end -0.7874 -0.4064)
			(stroke
				(width 0.1524)
				(type default)
			)
			(layer "F.SilkS")
		)
		(fp_line
			(start 0.7874 -0.4064)
			(end 0.7874 0.4064)
			(stroke
				(width 0.1524)
				(type default)
			)
			(layer "F.SilkS")
		)
		(fp_line
			(start 0.7874 0.4064)
			(end -0.7874 0.4064)
			(stroke
				(width 0.1524)
				(type default)
			)
			(layer "F.SilkS")
		)
		(fp_line
			(start -0.67945 -0.305054)
			(end -0.12065 -0.305054)
			(stroke
				(width 0.1)
				(type default)
			)
			(layer "F.Fab")
		)
		(fp_line
			(start -0.67945 0.3048)
			(end -0.67945 -0.305054)
			(stroke
				(width 0.1)
				(type default)
			)
			(layer "F.Fab")
		)
		(fp_line
			(start -0.12065 -0.305054)
			(end -0.12065 -0.2794)
			(stroke
				(width 0.1)
				(type default)
			)
			(layer "F.Fab")
		)
		(fp_line
			(start -0.12065 -0.2794)
			(end 0.12065 -0.2794)
			(stroke
				(width 0.1)
				(type default)
			)
			(layer "F.Fab")
		)
		(fp_line
			(start -0.12065 0.2794)
			(end -0.12065 0.3048)
			(stroke
				(width 0.1)
				(type default)
			)
			(layer "F.Fab")
		)
		(fp_line
			(start -0.12065 0.3048)
			(end -0.67945 0.3048)
			(stroke
				(width 0.1)
				(type default)
			)
			(layer "F.Fab")
		)
		(fp_line
			(start 0.120396 0.2794)
			(end -0.12065 0.2794)
			(stroke
				(width 0.1)
				(type default)
			)
			(layer "F.Fab")
		)
		(fp_line
			(start 0.120396 0.3048)
			(end 0.120396 0.2794)
			(stroke
				(width 0.1)
				(type default)
			)
			(layer "F.Fab")
		)
		(fp_line
			(start 0.12065 -0.3048)
			(end 0.67945 -0.3048)
			(stroke
				(width 0.1)
				(type default)
			)
			(layer "F.Fab")
		)
		(fp_line
			(start 0.12065 -0.2794)
			(end 0.12065 -0.3048)
			(stroke
				(width 0.1)
				(type default)
			)
			(layer "F.Fab")
		)
		(fp_line
			(start 0.67945 -0.3048)
			(end 0.67945 0.3048)
			(stroke
				(width 0.1)
				(type default)
			)
			(layer "F.Fab")
		)
		(fp_line
			(start 0.67945 0.3048)
			(end 0.120396 0.3048)
			(stroke
				(width 0.1)
				(type default)
			)
			(layer "F.Fab")
		)
		(pad "1" smd circle
			(at -0.40005 0)
			(size 0 0)
			(layers "F.Cu" "F.Mask" "F.Paste")
			(net "SSD5_ADC_A1")
		)
		(pad "2" smd circle
			(at 0.40005 0)
			(size 0 0)
			(layers "F.Cu" "F.Mask" "F.Paste")
			(net "GND")
		)
	)
)
